# S9S_MB_2U (Grand Teton) — schematic netlist excerpt (pin names and nets, part order shuffled) for the footprints in the layout excerpt that follows; sources: Cadence DE-HDL packaged netlist, KiCad conversion of 03242023_DA0F0TMBIJ0_F0T_Motherboard_J_brd_V01_OCP.brd

PC2182  Q_CAP  220PF 50V 10% X7R  pkg 0402  page 302 : A = HSC_ON ; B = AGND_HSC
R4061  Q_RES  0 5% EMPTY  pkg 0402LF  page 156 : A = HP_LVC3_OCP_V3_1_EN ; B = P12V_OCP_EN_1_R

(kicad_pcb
	(version 20260206)
	(generator "pcbnew")
	(generator_version "10.0")
	(general
		(thickness 1.6)
		(legacy_teardrops no)
	)
	(paper "A4")
	(title_block
		(title "03242023_DA0F0TMBIJ0_F0T_Motherboard_J_brd_V01_OCP.brd")
		(comment 1 "Grand Teton / footprints 2710-2711 of 6105")
	)
	(layers
		(0 "F.Cu" signal "TOP")
		(4 "In1.Cu" signal "GND")
		(6 "In2.Cu" signal "IN1")
		(8 "In3.Cu" signal "GND1")
		(10 "In4.Cu" signal "IN2")
		(12 "In5.Cu" signal "GND2")
		(14 "In6.Cu" signal "IN3")
		(16 "In7.Cu" signal "GND3")
		(18 "In8.Cu" signal "VCC")
		(20 "In9.Cu" signal "VCC1")
		(22 "In10.Cu" signal "GND4")
		(24 "In11.Cu" signal "IN4")
		(26 "In12.Cu" signal "GND5")
		(28 "In13.Cu" signal "IN5")
		(30 "In14.Cu" signal "GND6")
		(32 "In15.Cu" signal "IN6")
		(34 "In16.Cu" signal "GND7")
		(2 "B.Cu" signal "BOTTOM")
		(9 "F.Adhes" user "F.Adhesive")
		(11 "B.Adhes" user "B.Adhesive")
		(13 "F.Paste" user "Package Geometry/Pastemask Top")
		(15 "B.Paste" user "Package Geometry/Pastemask Bottom")
		(5 "F.SilkS" user "Ref Des/Silkscreen Top")
		(7 "B.SilkS" user "Ref Des/Silkscreen Bottom")
		(1 "F.Mask" user "Board Geometry/Soldermask Top")
		(3 "B.Mask" user "Board Geometry/Soldermask Bottom")
		(17 "Dwgs.User" user "User.Drawings")
		(19 "Cmts.User" user "User.Comments")
		(21 "Eco1.User" user "User.Eco1")
		(23 "Eco2.User" user "User.Eco2")
		(25 "Edge.Cuts" user "Board Geometry/Outline")
		(27 "Margin" user)
		(31 "F.CrtYd" user "Package Geometry/Place Bound Top")
		(29 "B.CrtYd" user "Package Geometry/Place Bound Bottom")
		(35 "F.Fab" user "Ref Des/Assembly Top")
		(33 "B.Fab" user "Ref Des/Assembly Bottom")
	)
	(footprint ""
		(layer "F.Cu")
		(at 205.397608 -404.823422)
		(property "Reference" "PC2182"
			(at 0 0 0)
			(layer "F.SilkS")
			(hide yes)
			(effects
				(font
					(size 1.27 1.27)
				)
			)
		)
		(property "Value" ""
			(at 0 0 0)
			(layer "F.Fab")
			(effects
				(font
					(size 1.27 1.27)
				)
			)
		)
		(duplicate_pad_numbers_are_jumpers no)
		(fp_line
			(start -0.7874 -0.4064)
			(end 0.7874 -0.4064)
			(stroke
				(width 0.1524)
				(type default)
			)
			(layer "F.SilkS")
		)
		(fp_line
			(start -0.7874 0.4064)
			(end -0.7874 -0.4064)
			(stroke
				(width 0.1524)
				(type default)
			)
			(layer "F.SilkS")
		)
		(fp_line
			(start 0.7874 -0.4064)
			(end 0.7874 0.4064)
			(stroke
				(width 0.1524)
				(type default)
			)
			(layer "F.SilkS")
		)
		(fp_line
			(start 0.7874 0.4064)
			(end -0.7874 0.4064)
			(stroke
				(width 0.1524)
				(type default)
			)
			(layer "F.SilkS")
		)
		(fp_line
			(start -0.67945 -0.305054)
			(end -0.12065 -0.305054)
			(stroke
				(width 0.1)
				(type default)
			)
			(layer "F.Fab")
		)
		(fp_line
			(start -0.67945 0.3048)
			(end -0.67945 -0.305054)
			(stroke
				(width 0.1)
				(type default)
			)
			(layer "F.Fab")
		)
		(fp_line
			(start -0.12065 -0.305054)
			(end -0.12065 -0.2794)
			(stroke
				(width 0.1)
				(type default)
			)
			(layer "F.Fab")
		)
		(fp_line
			(start -0.12065 -0.2794)
			(end 0.12065 -0.2794)
			(stroke
				(width 0.1)
				(type default)
			)
			(layer "F.Fab")
		)
		(fp_line
			(start -0.12065 0.2794)
			(end -0.12065 0.3048)
			(stroke
				(width 0.1)
				(type default)
			)
			(layer "F.Fab")
		)
		(fp_line
			(start -0.12065 0.3048)
			(end -0.67945 0.3048)
			(stroke
				(width 0.1)
				(type default)
			)
			(layer "F.Fab")
		)
		(fp_line
			(start 0.120396 0.2794)
			(end -0.12065 0.2794)
			(stroke
				(width 0.1)
				(type default)
			)
			(layer "F.Fab")
		)
		(fp_line
			(start 0.120396 0.3048)
			(end 0.120396 0.2794)
			(stroke
				(width 0.1)
				(type default)
			)
			(layer "F.Fab")
		)
		(fp_line
			(start 0.12065 -0.3048)
			(end 0.67945 -0.3048)
			(stroke
				(width 0.1)
				(type default)
			)
			(layer "F.Fab")
		)
		(fp_line
			(start 0.12065 -0.2794)
			(end 0.12065 -0.3048)
			(stroke
				(width 0.1)
				(type default)
			)
			(layer "F.Fab")
		)
		(fp_line
			(start 0.67945 -0.3048)
			(end 0.67945 0.3048)
			(stroke
				(width 0.1)
				(type default)
			)
			(layer "F.Fab")
		)
		(fp_line
			(start 0.67945 0.3048)
			(end 0.120396 0.3048)
			(stroke
				(width 0.1)
				(type default)
			)
			(layer "F.Fab")
		)
		(pad "1" smd circle
			(at -0.40005 0)
			(size 0 0)
			(layers "F.Cu" "F.Mask" "F.Paste")
			(net "HSC_ON")
		)
		(pad "2" smd circle
			(at 0.40005 0)
			(size 0 0)
			(layers "F.Cu" "F.Mask" "F.Paste")
			(net "AGND_HSC")
		)
	)
	(footprint ""
		(layer "F.Cu")
		(at 462.143094 -38.684454 90)
		(property "Reference" "R4061"
			(at 0 0 90)
			(layer "F.SilkS")
			(hide yes)
			(effects
				(font
					(size 1.27 1.27)
				)
			)
		)
		(property "Value" ""
			(at 0 0 90)
			(layer "F.Fab")
			(effects
				(font
					(size 1.27 1.27)
				)
			)
		)
		(duplicate_pad_numbers_are_jumpers no)
		(fp_line
			(start 0.7874 -0.4064)
			(end 0.7874 0.4064)
			(stroke
				(width 0.1524)
				(type default)
			)
			(layer "F.SilkS")
		)
		(fp_line
			(start -0.7874 -0.4064)
			(end 0.7874 -0.4064)
			(stroke
				(width 0.1524)
				(type default)
			)
			(layer "F.SilkS")
		)
		(fp_line
			(start 0.7874 0.4064)
			(end -0.7874 0.4064)
			(stroke
				(width 0.1524)
				(type default)
			)
			(layer "F.SilkS")
		)
		(fp_line
			(start -0.7874 0.4064)
			(end -0.7874 -0.4064)
			(stroke
				(width 0.1524)
				(type default)
			)
			(layer "F.SilkS")
		)
		(fp_line
			(start -0.12065 -0.305054)
			(end -0.12065 -0.2794)
			(stroke
				(width 0.1)
				(type default)
			)
			(layer "F.Fab")
		)
		(fp_line
			(start -0.67945 -0.305054)
			(end -0.12065 -0.305054)
			(stroke
				(width 0.1)
				(type default)
			)
			(layer "F.Fab")
		)
		(fp_line
			(start 0.67945 -0.3048)
			(end 0.67945 0.3048)
			(stroke
				(width 0.1)
				(type default)
			)
			(layer "F.Fab")
		)
		(fp_line
			(start 0.12065 -0.3048)
			(end 0.67945 -0.3048)
			(stroke
				(width 0.1)
				(type default)
			)
			(layer "F.Fab")
		)
		(fp_line
			(start 0.12065 -0.2794)
			(end 0.12065 -0.3048)
			(stroke
				(width 0.1)
				(type default)
			)
			(layer "F.Fab")
		)
		(fp_line
			(start -0.12065 -0.2794)
			(end 0.12065 -0.2794)
			(stroke
				(width 0.1)
				(type default)
			)
			(layer "F.Fab")
		)
		(fp_line
			(start 0.120396 0.2794)
			(end -0.12065 0.2794)
			(stroke
				(width 0.1)
				(type default)
			)
			(layer "F.Fab")
		)
		(fp_line
			(start -0.12065 0.2794)
			(end -0.12065 0.3048)
			(stroke
				(width 0.1)
				(type default)
			)
			(layer "F.Fab")
		)
		(fp_line
			(start 0.67945 0.3048)
			(end 0.120396 0.3048)
			(stroke
				(width 0.1)
				(type default)
			)
			(layer "F.Fab")
		)
		(fp_line
			(start 0.120396 0.3048)
			(end 0.120396 0.2794)
			(stroke
				(width 0.1)
				(type default)
			)
			(layer "F.Fab")
		)
		(fp_line
			(start -0.12065 0.3048)
			(end -0.67945 0.3048)
			(stroke
				(width 0.1)
				(type default)
			)
			(layer "F.Fab")
		)
		(fp_line
			(start -0.67945 0.3048)
			(end -0.67945 -0.305054)
			(stroke
				(width 0.1)
				(type default)
			)
			(layer "F.Fab")
		)
		(pad "1" smd circle
			(at -0.40005 0 90)
			(size 0 0)
			(layers "F.Cu" "F.Mask" "F.Paste")
			(net "HP_LVC3_OCP_V3_1_EN")
		)
		(pad "2" smd circle
			(at 0.40005 0 90)
			(size 0 0)
			(layers "F.Cu" "F.Mask" "F.Paste")
			(net "P12V_OCP_EN_1_R")
		)
	)
)
